# SCM (Grand Teton) — schematic netlist excerpt (pin names and nets, part order shuffled) for the footprints in the layout excerpt that follows; sources: Cadence DE-HDL packaged netlist, KiCad conversion of 12092022_DA0F0TMDCD0_F0T_Management_Board_D_brd_V3_OCP.brd

R13  Q_RES  4.7K 1% EMPTY  pkg 0402LF  page 26 : A = P3V3_AUX ; B = FRU_E1
R131  Q_RES  22 1% CHIP  pkg 0402LF  page 12 : A = ESPI_LPC_D3_IO3 ; B = ESPI_LPC_LAD3_IO3

(kicad_pcb
	(version 20260206)
	(generator "pcbnew")
	(generator_version "10.0")
	(general
		(thickness 1.6)
		(legacy_teardrops no)
	)
	(paper "A4")
	(title_block
		(title "12092022_DA0F0TMDCD0_F0T_Management_Board_D_brd_V3_OCP.brd")
		(comment 1 "Grand Teton / footprints 841-842 of 1440")
	)
	(layers
		(0 "F.Cu" signal "TOP")
		(4 "In1.Cu" signal "GND")
		(6 "In2.Cu" signal "IN1")
		(8 "In3.Cu" signal "GND1")
		(10 "In4.Cu" signal "IN2")
		(12 "In5.Cu" signal "VCC")
		(14 "In6.Cu" signal "VCC1")
		(16 "In7.Cu" signal "IN3")
		(18 "In8.Cu" signal "GND2")
		(20 "In9.Cu" signal "IN4")
		(22 "In10.Cu" signal "GND3")
		(2 "B.Cu" signal "BOTTOM")
		(9 "F.Adhes" user "F.Adhesive")
		(11 "B.Adhes" user "B.Adhesive")
		(13 "F.Paste" user "Package Geometry/Pastemask Top")
		(15 "B.Paste" user "Package Geometry/Pastemask Bottom")
		(5 "F.SilkS" user "Ref Des/Silkscreen Top")
		(7 "B.SilkS" user "Ref Des/Silkscreen Bottom")
		(1 "F.Mask" user "Board Geometry/Soldermask Top")
		(3 "B.Mask" user "Board Geometry/Soldermask Bottom")
		(17 "Dwgs.User" user "User.Drawings")
		(19 "Cmts.User" user "User.Comments")
		(21 "Eco1.User" user "User.Eco1")
		(23 "Eco2.User" user "User.Eco2")
		(25 "Edge.Cuts" user "Board Geometry/Outline")
		(27 "Margin" user)
		(31 "F.CrtYd" user "Package Geometry/Place Bound Top")
		(29 "B.CrtYd" user "Package Geometry/Place Bound Bottom")
		(35 "F.Fab" user "Ref Des/Assembly Top")
		(33 "B.Fab" user "Ref Des/Assembly Bottom")
	)
	(footprint ""
		(layer "B.Cu")
		(at 63.61811 -62.014862 -90)
		(property "Reference" "R131"
			(at 0 0 90)
			(layer "B.SilkS")
			(hide yes)
			(effects
				(font
					(size 1.27 1.27)
				)
				(justify mirror)
			)
		)
		(property "Value" ""
			(at 0 0 90)
			(layer "B.Fab")
			(effects
				(font
					(size 1.27 1.27)
				)
				(justify mirror)
			)
		)
		(duplicate_pad_numbers_are_jumpers no)
		(fp_line
			(start -0.7874 0.4064)
			(end 0.7874 0.4064)
			(stroke
				(width 0.1524)
				(type default)
			)
			(layer "B.SilkS")
		)
		(fp_line
			(start 0.7874 0.4064)
			(end 0.7874 -0.4064)
			(stroke
				(width 0.1524)
				(type default)
			)
			(layer "B.SilkS")
		)
		(fp_line
			(start -0.7874 -0.4064)
			(end -0.7874 0.4064)
			(stroke
				(width 0.1524)
				(type default)
			)
			(layer "B.SilkS")
		)
		(fp_line
			(start 0.7874 -0.4064)
			(end -0.7874 -0.4064)
			(stroke
				(width 0.1524)
				(type default)
			)
			(layer "B.SilkS")
		)
		(fp_line
			(start -0.67945 0.3048)
			(end -0.120396 0.3048)
			(stroke
				(width 0.1)
				(type default)
			)
			(layer "B.Fab")
		)
		(fp_line
			(start -0.120396 0.3048)
			(end -0.120396 0.2794)
			(stroke
				(width 0.1)
				(type default)
			)
			(layer "B.Fab")
		)
		(fp_line
			(start 0.12065 0.3048)
			(end 0.67945 0.3048)
			(stroke
				(width 0.1)
				(type default)
			)
			(layer "B.Fab")
		)
		(fp_line
			(start 0.67945 0.3048)
			(end 0.67945 -0.305054)
			(stroke
				(width 0.1)
				(type default)
			)
			(layer "B.Fab")
		)
		(fp_line
			(start -0.120396 0.2794)
			(end 0.12065 0.2794)
			(stroke
				(width 0.1)
				(type default)
			)
			(layer "B.Fab")
		)
		(fp_line
			(start 0.12065 0.2794)
			(end 0.12065 0.3048)
			(stroke
				(width 0.1)
				(type default)
			)
			(layer "B.Fab")
		)
		(fp_line
			(start -0.12065 -0.2794)
			(end -0.12065 -0.3048)
			(stroke
				(width 0.1)
				(type default)
			)
			(layer "B.Fab")
		)
		(fp_line
			(start 0.12065 -0.2794)
			(end -0.12065 -0.2794)
			(stroke
				(width 0.1)
				(type default)
			)
			(layer "B.Fab")
		)
		(fp_line
			(start -0.67945 -0.3048)
			(end -0.67945 0.3048)
			(stroke
				(width 0.1)
				(type default)
			)
			(layer "B.Fab")
		)
		(fp_line
			(start -0.12065 -0.3048)
			(end -0.67945 -0.3048)
			(stroke
				(width 0.1)
				(type default)
			)
			(layer "B.Fab")
		)
		(fp_line
			(start 0.12065 -0.305054)
			(end 0.12065 -0.2794)
			(stroke
				(width 0.1)
				(type default)
			)
			(layer "B.Fab")
		)
		(fp_line
			(start 0.67945 -0.305054)
			(end 0.12065 -0.305054)
			(stroke
				(width 0.1)
				(type default)
			)
			(layer "B.Fab")
		)
		(pad "1" smd circle
			(at 0.40005 0 90)
			(size 0 0)
			(layers "B.Cu" "B.Mask" "B.Paste")
			(net "ESPI_LPC_D3_IO3")
		)
		(pad "2" smd circle
			(at -0.40005 0 90)
			(size 0 0)
			(layers "B.Cu" "B.Mask" "B.Paste")
			(net "ESPI_LPC_LAD3_IO3")
		)
	)
	(footprint ""
		(layer "B.Cu")
		(at 85.32241 -27.607768)
		(property "Reference" "R13"
			(at 0 0 0)
			(layer "B.SilkS")
			(hide yes)
			(effects
				(font
					(size 1.27 1.27)
				)
				(justify mirror)
			)
		)
		(property "Value" ""
			(at 0 0 0)
			(layer "B.Fab")
			(effects
				(font
					(size 1.27 1.27)
				)
				(justify mirror)
			)
		)
		(duplicate_pad_numbers_are_jumpers no)
		(fp_line
			(start -0.7874 -0.4064)
			(end -0.7874 0.4064)
			(stroke
				(width 0.1524)
				(type default)
			)
			(layer "B.SilkS")
		)
		(fp_line
			(start -0.7874 0.4064)
			(end 0.7874 0.4064)
			(stroke
				(width 0.1524)
				(type default)
			)
			(layer "B.SilkS")
		)
		(fp_line
			(start 0.7874 -0.4064)
			(end -0.7874 -0.4064)
			(stroke
				(width 0.1524)
				(type default)
			)
			(layer "B.SilkS")
		)
		(fp_line
			(start 0.7874 0.4064)
			(end 0.7874 -0.4064)
			(stroke
				(width 0.1524)
				(type default)
			)
			(layer "B.SilkS")
		)
		(fp_line
			(start -0.67945 -0.3048)
			(end -0.67945 0.3048)
			(stroke
				(width 0.1)
				(type default)
			)
			(layer "B.Fab")
		)
		(fp_line
			(start -0.67945 0.3048)
			(end -0.120396 0.3048)
			(stroke
				(width 0.1)
				(type default)
			)
			(layer "B.Fab")
		)
		(fp_line
			(start -0.12065 -0.3048)
			(end -0.67945 -0.3048)
			(stroke
				(width 0.1)
				(type default)
			)
			(layer "B.Fab")
		)
		(fp_line
			(start -0.12065 -0.2794)
			(end -0.12065 -0.3048)
			(stroke
				(width 0.1)
				(type default)
			)
			(layer "B.Fab")
		)
		(fp_line
			(start -0.120396 0.2794)
			(end 0.12065 0.2794)
			(stroke
				(width 0.1)
				(type default)
			)
			(layer "B.Fab")
		)
		(fp_line
			(start -0.120396 0.3048)
			(end -0.120396 0.2794)
			(stroke
				(width 0.1)
				(type default)
			)
			(layer "B.Fab")
		)
		(fp_line
			(start 0.12065 -0.305054)
			(end 0.12065 -0.2794)
			(stroke
				(width 0.1)
				(type default)
			)
			(layer "B.Fab")
		)
		(fp_line
			(start 0.12065 -0.2794)
			(end -0.12065 -0.2794)
			(stroke
				(width 0.1)
				(type default)
			)
			(layer "B.Fab")
		)
		(fp_line
			(start 0.12065 0.2794)
			(end 0.12065 0.3048)
			(stroke
				(width 0.1)
				(type default)
			)
			(layer "B.Fab")
		)
		(fp_line
			(start 0.12065 0.3048)
			(end 0.67945 0.3048)
			(stroke
				(width 0.1)
				(type default)
			)
			(layer "B.Fab")
		)
		(fp_line
			(start 0.67945 -0.305054)
			(end 0.12065 -0.305054)
			(stroke
				(width 0.1)
				(type default)
			)
			(layer "B.Fab")
		)
		(fp_line
			(start 0.67945 0.3048)
			(end 0.67945 -0.305054)
			(stroke
				(width 0.1)
				(type default)
			)
			(layer "B.Fab")
		)
		(pad "1" smd circle
			(at 0.40005 0 180)
			(size 0 0)
			(layers "B.Cu" "B.Mask" "B.Paste")
			(net "P3V3_AUX")
		)
		(pad "2" smd circle
			(at -0.40005 0 180)
			(size 0 0)
			(layers "B.Cu" "B.Mask" "B.Paste")
			(net "FRU_E1")
		)
	)
)
